# S9S_MB_2U (Grand Teton) — schematic netlist excerpt (pin names and nets, part order shuffled) for the footprints in the layout excerpt that follows; sources: Cadence DE-HDL packaged netlist, KiCad conversion of 03242023_DA0F0TMBIJ0_F0T_Motherboard_J_brd_V01_OCP.brd

C1142  Q_CAP  0.01UF 50V 10% X7R  pkg C0402  page 217 : A = P3V3_AUX_FPGA_VCCIO2 ; B = GND
PR4218  Q_RES  0 5% EMPTY  pkg 0402LF  page 266 : A = PVCCFA_EHV_FIVRA_CPU0_IMON3 ; B = GND

(kicad_pcb
	(version 20260206)
	(generator "pcbnew")
	(generator_version "10.0")
	(general
		(thickness 1.6)
		(legacy_teardrops no)
	)
	(paper "A4")
	(title_block
		(title "03242023_DA0F0TMBIJ0_F0T_Motherboard_J_brd_V01_OCP.brd")
		(comment 1 "Grand Teton / footprints 5179-5180 of 6105")
	)
	(layers
		(0 "F.Cu" signal "TOP")
		(4 "In1.Cu" signal "GND")
		(6 "In2.Cu" signal "IN1")
		(8 "In3.Cu" signal "GND1")
		(10 "In4.Cu" signal "IN2")
		(12 "In5.Cu" signal "GND2")
		(14 "In6.Cu" signal "IN3")
		(16 "In7.Cu" signal "GND3")
		(18 "In8.Cu" signal "VCC")
		(20 "In9.Cu" signal "VCC1")
		(22 "In10.Cu" signal "GND4")
		(24 "In11.Cu" signal "IN4")
		(26 "In12.Cu" signal "GND5")
		(28 "In13.Cu" signal "IN5")
		(30 "In14.Cu" signal "GND6")
		(32 "In15.Cu" signal "IN6")
		(34 "In16.Cu" signal "GND7")
		(2 "B.Cu" signal "BOTTOM")
		(9 "F.Adhes" user "F.Adhesive")
		(11 "B.Adhes" user "B.Adhesive")
		(13 "F.Paste" user "Package Geometry/Pastemask Top")
		(15 "B.Paste" user "Package Geometry/Pastemask Bottom")
		(5 "F.SilkS" user "Ref Des/Silkscreen Top")
		(7 "B.SilkS" user "Ref Des/Silkscreen Bottom")
		(1 "F.Mask" user "Board Geometry/Soldermask Top")
		(3 "B.Mask" user "Board Geometry/Soldermask Bottom")
		(17 "Dwgs.User" user "User.Drawings")
		(19 "Cmts.User" user "User.Comments")
		(21 "Eco1.User" user "User.Eco1")
		(23 "Eco2.User" user "User.Eco2")
		(25 "Edge.Cuts" user "Board Geometry/Outline")
		(27 "Margin" user)
		(31 "F.CrtYd" user "Package Geometry/Place Bound Top")
		(29 "B.CrtYd" user "Package Geometry/Place Bound Bottom")
		(35 "F.Fab" user "Ref Des/Assembly Top")
		(33 "B.Fab" user "Ref Des/Assembly Bottom")
	)
	(footprint ""
		(layer "B.Cu")
		(at 357.368602 -356.50043 -90)
		(property "Reference" "PR4218"
			(at 0 0 90)
			(layer "B.SilkS")
			(hide yes)
			(effects
				(font
					(size 1.27 1.27)
				)
				(justify mirror)
			)
		)
		(property "Value" ""
			(at 0 0 90)
			(layer "B.Fab")
			(effects
				(font
					(size 1.27 1.27)
				)
				(justify mirror)
			)
		)
		(duplicate_pad_numbers_are_jumpers no)
		(fp_line
			(start -0.7874 0.4064)
			(end 0.7874 0.4064)
			(stroke
				(width 0.1524)
				(type default)
			)
			(layer "B.SilkS")
		)
		(fp_line
			(start 0.7874 0.4064)
			(end 0.7874 -0.4064)
			(stroke
				(width 0.1524)
				(type default)
			)
			(layer "B.SilkS")
		)
		(fp_line
			(start -0.7874 -0.4064)
			(end -0.7874 0.4064)
			(stroke
				(width 0.1524)
				(type default)
			)
			(layer "B.SilkS")
		)
		(fp_line
			(start 0.7874 -0.4064)
			(end -0.7874 -0.4064)
			(stroke
				(width 0.1524)
				(type default)
			)
			(layer "B.SilkS")
		)
		(fp_line
			(start -0.67945 0.3048)
			(end -0.120396 0.3048)
			(stroke
				(width 0.1)
				(type default)
			)
			(layer "B.Fab")
		)
		(fp_line
			(start -0.120396 0.3048)
			(end -0.120396 0.2794)
			(stroke
				(width 0.1)
				(type default)
			)
			(layer "B.Fab")
		)
		(fp_line
			(start 0.12065 0.3048)
			(end 0.67945 0.3048)
			(stroke
				(width 0.1)
				(type default)
			)
			(layer "B.Fab")
		)
		(fp_line
			(start 0.67945 0.3048)
			(end 0.67945 -0.305054)
			(stroke
				(width 0.1)
				(type default)
			)
			(layer "B.Fab")
		)
		(fp_line
			(start -0.120396 0.2794)
			(end 0.12065 0.2794)
			(stroke
				(width 0.1)
				(type default)
			)
			(layer "B.Fab")
		)
		(fp_line
			(start 0.12065 0.2794)
			(end 0.12065 0.3048)
			(stroke
				(width 0.1)
				(type default)
			)
			(layer "B.Fab")
		)
		(fp_line
			(start -0.12065 -0.2794)
			(end -0.12065 -0.3048)
			(stroke
				(width 0.1)
				(type default)
			)
			(layer "B.Fab")
		)
		(fp_line
			(start 0.12065 -0.2794)
			(end -0.12065 -0.2794)
			(stroke
				(width 0.1)
				(type default)
			)
			(layer "B.Fab")
		)
		(fp_line
			(start -0.67945 -0.3048)
			(end -0.67945 0.3048)
			(stroke
				(width 0.1)
				(type default)
			)
			(layer "B.Fab")
		)
		(fp_line
			(start -0.12065 -0.3048)
			(end -0.67945 -0.3048)
			(stroke
				(width 0.1)
				(type default)
			)
			(layer "B.Fab")
		)
		(fp_line
			(start 0.12065 -0.305054)
			(end 0.12065 -0.2794)
			(stroke
				(width 0.1)
				(type default)
			)
			(layer "B.Fab")
		)
		(fp_line
			(start 0.67945 -0.305054)
			(end 0.12065 -0.305054)
			(stroke
				(width 0.1)
				(type default)
			)
			(layer "B.Fab")
		)
		(pad "1" smd circle
			(at 0.40005 0 90)
			(size 0 0)
			(layers "B.Cu" "B.Mask" "B.Paste")
			(net "PVCCFA_EHV_FIVRA_CPU0_IMON3")
		)
		(pad "2" smd circle
			(at -0.40005 0 90)
			(size 0 0)
			(layers "B.Cu" "B.Mask" "B.Paste")
			(net "GND")
		)
	)
	(footprint ""
		(layer "B.Cu")
		(at 181.755542 -112.175544)
		(property "Reference" "C1142"
			(at 0 0 0)
			(layer "B.SilkS")
			(hide yes)
			(effects
				(font
					(size 1.27 1.27)
				)
				(justify mirror)
			)
		)
		(property "Value" ""
			(at 0 0 0)
			(layer "B.Fab")
			(effects
				(font
					(size 1.27 1.27)
				)
				(justify mirror)
			)
		)
		(duplicate_pad_numbers_are_jumpers no)
		(fp_line
			(start -0.69215 -0.2921)
			(end -0.69215 0.2921)
			(stroke
				(width 0.1524)
				(type default)
			)
			(layer "B.SilkS")
		)
		(fp_line
			(start -0.69215 0.2921)
			(end 0.69215 0.2921)
			(stroke
				(width 0.1524)
				(type default)
			)
			(layer "B.SilkS")
		)
		(fp_line
			(start 0.69215 -0.2921)
			(end -0.69215 -0.2921)
			(stroke
				(width 0.1524)
				(type default)
			)
			(layer "B.SilkS")
		)
		(fp_line
			(start 0.69215 0.2921)
			(end 0.69215 -0.2921)
			(stroke
				(width 0.1524)
				(type default)
			)
			(layer "B.SilkS")
		)
		(fp_line
			(start -0.51435 -0.2794)
			(end -0.51435 0.2794)
			(stroke
				(width 0.1)
				(type default)
			)
			(layer "B.Fab")
		)
		(fp_line
			(start -0.51435 0.2794)
			(end 0.51435 0.2794)
			(stroke
				(width 0.1)
				(type default)
			)
			(layer "B.Fab")
		)
		(fp_line
			(start 0.51435 -0.2794)
			(end -0.51435 -0.2794)
			(stroke
				(width 0.1)
				(type default)
			)
			(layer "B.Fab")
		)
		(fp_line
			(start 0.51435 0.2794)
			(end 0.51435 -0.2794)
			(stroke
				(width 0.1)
				(type default)
			)
			(layer "B.Fab")
		)
		(pad "1" smd circle
			(at 0.40005 0 180)
			(size 0 0)
			(layers "B.Cu" "B.Mask" "B.Paste")
			(net "P3V3_AUX_FPGA_VCCIO2")
		)
		(pad "2" smd circle
			(at -0.40005 0 180)
			(size 0 0)
			(layers "B.Cu" "B.Mask" "B.Paste")
			(net "GND")
		)
		(zone
			(layer "B.Cu")
			(hatch none 0.5)
			(connect_pads
				(clearance 0)
			)
			(min_thickness 0.25)
			(keepout
				(tracks not_allowed)
				(vias allowed)
				(pads allowed)
				(copperpour not_allowed)
				(footprints allowed)
			)
			(placement
				(enabled no)
				(sheetname "")
			)
			(fill
				(thermal_gap 0.5)
				(thermal_bridge_width 0.5)
				(island_removal_mode 0)
			)
			(polygon
				(pts
					(xy 181.946042 -112.087914) (xy 181.854602 -112.029748) (xy 181.655212 -112.029748) (xy 181.565042 -112.087914)
					(xy 181.565042 -112.263174) (xy 181.655212 -112.321594) (xy 181.854602 -112.321594) (xy 181.946042 -112.263428)
				)
			)
		)
	)
)
